# T6G (Grand Teton) — schematic netlist excerpt (pin names and nets, part order shuffled) for the footprints in the layout excerpt that follows; sources: Cadence DE-HDL packaged netlist, KiCad conversion of 04192023_DAF0TMB3IC0_F0TG_MB_C_brd_V02_OCP.brd

PD13  ZENER_AC  5.0SMDJ14A IC  pkg D2723_SMCXC  page 268 : A = GND ; C = P12V_PSU_FUSE

(kicad_pcb
	(version 20260206)
	(generator "pcbnew")
	(generator_version "10.0")
	(general
		(thickness 1.6)
		(legacy_teardrops no)
	)
	(paper "A4")
	(title_block
		(title "04192023_DAF0TMB3IC0_F0TG_MB_C_brd_V02_OCP.brd")
		(comment 1 "Grand Teton / footprints 2018-2018 of 8354")
	)
	(layers
		(0 "F.Cu" signal "TOP")
		(4 "In1.Cu" signal "GND")
		(6 "In2.Cu" signal "IN1")
		(8 "In3.Cu" signal "GND1")
		(10 "In4.Cu" signal "IN2")
		(12 "In5.Cu" signal "GND2")
		(14 "In6.Cu" signal "IN3")
		(16 "In7.Cu" signal "GND3")
		(18 "In8.Cu" signal "VCC")
		(20 "In9.Cu" signal "VCC1")
		(22 "In10.Cu" signal "GND4")
		(24 "In11.Cu" signal "IN4")
		(26 "In12.Cu" signal "GND5")
		(28 "In13.Cu" signal "IN5")
		(30 "In14.Cu" signal "GND6")
		(32 "In15.Cu" signal "IN6")
		(34 "In16.Cu" signal "GND7")
		(2 "B.Cu" signal "BOTTOM")
		(9 "F.Adhes" user "F.Adhesive")
		(11 "B.Adhes" user "B.Adhesive")
		(13 "F.Paste" user "Package Geometry/Pastemask Top")
		(15 "B.Paste" user "Package Geometry/Pastemask Bottom")
		(5 "F.SilkS" user "Ref Des/Silkscreen Top")
		(7 "B.SilkS" user "Ref Des/Silkscreen Bottom")
		(1 "F.Mask" user "Board Geometry/Soldermask Top")
		(3 "B.Mask" user "Board Geometry/Soldermask Bottom")
		(17 "Dwgs.User" user "User.Drawings")
		(19 "Cmts.User" user "User.Comments")
		(21 "Eco1.User" user "User.Eco1")
		(23 "Eco2.User" user "User.Eco2")
		(25 "Edge.Cuts" user "Board Geometry/Outline")
		(27 "Margin" user)
		(31 "F.CrtYd" user "Package Geometry/Place Bound Top")
		(29 "B.CrtYd" user "Package Geometry/Place Bound Bottom")
		(35 "F.Fab" user "Ref Des/Assembly Top")
		(33 "B.Fab" user "Ref Des/Assembly Bottom")
	)
	(footprint ""
		(layer "F.Cu")
		(at 253.063756 -418.11067 -90)
		(property "Reference" "PD13"
			(at -1.69926 -3.99034 90)
			(unlocked yes)
			(layer "F.SilkS")
			(effects
				(font
					(size 0.7874 0.5842)
					(thickness 0.1524)
				)
				(justify left)
			)
		)
		(property "Value" ""
			(at 0 0 270)
			(layer "F.Fab")
			(effects
				(font
					(size 1.27 1.27)
				)
			)
		)
		(duplicate_pad_numbers_are_jumpers no)
		(fp_line
			(start -4.664456 3.109976)
			(end -4.664456 -3.109976)
			(stroke
				(width 0.1524)
				(type default)
			)
			(layer "F.SilkS")
		)
		(fp_line
			(start 4.156202 3.109976)
			(end 4.183126 3.109976)
			(stroke
				(width 0.1524)
				(type default)
			)
			(layer "F.SilkS")
		)
		(fp_line
			(start 4.743704 3.109976)
			(end 4.6101 3.109976)
			(stroke
				(width 0.1524)
				(type default)
			)
			(layer "F.SilkS")
		)
		(fp_line
			(start 4.743704 3.109976)
			(end 5.4102 3.109976)
			(stroke
				(width 0.1524)
				(type default)
			)
			(layer "F.SilkS")
		)
		(fp_line
			(start 4.769104 3.109976)
			(end -4.664456 3.109976)
			(stroke
				(width 0.1524)
				(type default)
			)
			(layer "F.SilkS")
		)
		(fp_line
			(start 4.794504 3.109976)
			(end 3.554984 3.109976)
			(stroke
				(width 0.1524)
				(type default)
			)
			(layer "F.SilkS")
		)
		(fp_line
			(start 5.4102 3.109976)
			(end 5.4102 -3.109976)
			(stroke
				(width 0.1524)
				(type default)
			)
			(layer "F.SilkS")
		)
		(fp_line
			(start 4.715002 3.035554)
			(end 4.7117 2.984754)
			(stroke
				(width 0.1524)
				(type default)
			)
			(layer "F.SilkS")
		)
		(fp_line
			(start 0.762 1.27)
			(end 0.762 -1.27)
			(stroke
				(width 0.1524)
				(type default)
			)
			(layer "F.SilkS")
		)
		(fp_line
			(start -0.508 1.016)
			(end -0.508 -1.016)
			(stroke
				(width 0.1524)
				(type default)
			)
			(layer "F.SilkS")
		)
		(fp_line
			(start -1.0668 0)
			(end -0.6096 0)
			(stroke
				(width 0.1524)
				(type default)
			)
			(layer "F.SilkS")
		)
		(fp_line
			(start 0.762 0)
			(end -0.508 1.016)
			(stroke
				(width 0.1524)
				(type default)
			)
			(layer "F.SilkS")
		)
		(fp_line
			(start 0.762 0)
			(end 1.2192 0)
			(stroke
				(width 0.1524)
				(type default)
			)
			(layer "F.SilkS")
		)
		(fp_line
			(start -0.508 -1.016)
			(end 0.762 0)
			(stroke
				(width 0.1524)
				(type default)
			)
			(layer "F.SilkS")
		)
		(fp_line
			(start -4.664456 -3.109976)
			(end 4.743704 -3.109976)
			(stroke
				(width 0.1524)
				(type default)
			)
			(layer "F.SilkS")
		)
		(fp_line
			(start 4.183126 -3.109976)
			(end 4.794504 -3.109976)
			(stroke
				(width 0.1524)
				(type default)
			)
			(layer "F.SilkS")
		)
		(fp_line
			(start 4.511802 -3.109976)
			(end 4.207002 -3.109976)
			(stroke
				(width 0.1524)
				(type default)
			)
			(layer "F.SilkS")
		)
		(fp_line
			(start 4.6101 -3.109976)
			(end 4.283202 -3.109976)
			(stroke
				(width 0.1524)
				(type default)
			)
			(layer "F.SilkS")
		)
		(fp_line
			(start 4.695444 -3.109976)
			(end 4.695444 3.109976)
			(stroke
				(width 0.1524)
				(type default)
			)
			(layer "F.SilkS")
		)
		(fp_line
			(start 4.70535 -3.109976)
			(end 4.70535 3.109976)
			(stroke
				(width 0.1524)
				(type default)
			)
			(layer "F.SilkS")
		)
		(fp_line
			(start 4.70535 -3.109976)
			(end 4.70535 3.109976)
			(stroke
				(width 0.1524)
				(type default)
			)
			(layer "F.SilkS")
		)
		(fp_line
			(start 4.70535 -3.109976)
			(end 4.70535 3.109976)
			(stroke
				(width 0.1524)
				(type default)
			)
			(layer "F.SilkS")
		)
		(fp_line
			(start 4.805426 -3.109976)
			(end 4.805426 3.109976)
			(stroke
				(width 0.1524)
				(type default)
			)
			(layer "F.SilkS")
		)
		(fp_line
			(start 4.932426 -3.109976)
			(end 4.932426 3.109976)
			(stroke
				(width 0.1524)
				(type default)
			)
			(layer "F.SilkS")
		)
		(fp_line
			(start 5.008626 -3.109976)
			(end 5.008626 3.109976)
			(stroke
				(width 0.1524)
				(type default)
			)
			(layer "F.SilkS")
		)
		(fp_line
			(start 5.110226 -3.109976)
			(end 5.110226 3.109976)
			(stroke
				(width 0.1524)
				(type default)
			)
			(layer "F.SilkS")
		)
		(fp_line
			(start 5.211826 -3.109976)
			(end 5.211826 3.109976)
			(stroke
				(width 0.1524)
				(type default)
			)
			(layer "F.SilkS")
		)
		(fp_line
			(start 5.262626 -3.109976)
			(end 5.262626 3.109976)
			(stroke
				(width 0.1524)
				(type default)
			)
			(layer "F.SilkS")
		)
		(fp_line
			(start 5.313426 -3.109976)
			(end 5.313426 3.109976)
			(stroke
				(width 0.1524)
				(type default)
			)
			(layer "F.SilkS")
		)
		(fp_line
			(start 5.4102 -3.109976)
			(end 4.783074 -3.109976)
			(stroke
				(width 0.1524)
				(type default)
			)
			(layer "F.SilkS")
		)
		(fp_line
			(start -4.065016 3.109976)
			(end -4.065016 -3.109976)
			(stroke
				(width 0.1)
				(type default)
			)
			(layer "F.Fab")
		)
		(fp_line
			(start 4.065016 3.109976)
			(end -4.065016 3.109976)
			(stroke
				(width 0.1)
				(type default)
			)
			(layer "F.Fab")
		)
		(fp_line
			(start -4.065016 -3.109976)
			(end 4.065016 -3.109976)
			(stroke
				(width 0.1)
				(type default)
			)
			(layer "F.Fab")
		)
		(fp_line
			(start 4.065016 -3.109976)
			(end 4.065016 3.109976)
			(stroke
				(width 0.1)
				(type default)
			)
			(layer "F.Fab")
		)
		(fp_text user "-"
			(at 6.643624 0.40005 90)
			(unlocked yes)
			(layer "F.SilkS")
			(effects
				(font
					(size 1.905 1.4224)
					(thickness 0.1524)
				)
				(justify left)
			)
		)
		(fp_text user "+"
			(at -4.5974 0.24765 90)
			(unlocked yes)
			(layer "F.SilkS")
			(effects
				(font
					(size 1.905 1.4224)
					(thickness 0.1524)
				)
				(justify left)
			)
		)
		(fp_text user "-"
			(at 6.643624 0.40005 90)
			(unlocked yes)
			(layer "F.Fab")
			(effects
				(font
					(size 1.905 1.4224)
					(thickness 0.1524)
				)
				(justify left)
			)
		)
		(fp_text user "+"
			(at -4.5974 0.24765 90)
			(unlocked yes)
			(layer "F.Fab")
			(effects
				(font
					(size 1.905 1.4224)
					(thickness 0.1524)
				)
				(justify left)
			)
		)
		(pad "A" smd rect
			(at -3.299968 0 90)
			(size 2.413 3.302)
			(layers "F.Cu" "F.Mask" "F.Paste")
			(net "GND")
		)
		(pad "C" smd rect
			(at 3.299968 0 90)
			(size 2.413 3.302)
			(layers "F.Cu" "F.Mask" "F.Paste")
			(net "P12V_PSU_FUSE")
		)
	)
)
